(kicad_pcb
	(version 20241229)
	(generator "pcbnew")
	(generator_version "9.0")
	(general
		(thickness 1.61)
		(legacy_teardrops no)
	)
	(paper "A3")
	(title_block
		(title "RDIMM DDR5 Tester")
		(date "2026-05-21")
		(rev "2.2.0")
		(company "Antmicro")
		(comment 9 "footprints 693-697 of 796")
	)
	(layers
		(0 "F.Cu" signal)
		(4 "In1.Cu" power)
		(6 "In2.Cu" mixed)
		(8 "In3.Cu" power)
		(10 "In4.Cu" mixed)
		(12 "In5.Cu" power)
		(14 "In6.Cu" mixed)
		(16 "In7.Cu" power)
		(18 "In8.Cu" power)
		(20 "In9.Cu" mixed)
		(22 "In10.Cu" power)
		(2 "B.Cu" signal)
		(9 "F.Adhes" user "F.Adhesive")
		(11 "B.Adhes" user "B.Adhesive")
		(13 "F.Paste" user)
		(15 "B.Paste" user)
		(5 "F.SilkS" user "F.Silkscreen")
		(7 "B.SilkS" user "B.Silkscreen")
		(1 "F.Mask" user)
		(3 "B.Mask" user)
		(17 "Dwgs.User" user "User.Drawings")
		(19 "Cmts.User" user "User.Comments")
		(21 "Eco1.User" user "User.Eco1")
		(23 "Eco2.User" user "User.Eco2")
		(25 "Edge.Cuts" user)
		(27 "Margin" user)
		(31 "F.CrtYd" user "F.Courtyard")
		(29 "B.CrtYd" user "B.Courtyard")
		(35 "F.Fab" user)
		(33 "B.Fab" user)
	)
	(footprint "antmicro-footprints:C_0402_1005Metric"
		(layer "B.Cu")
		(at 188.4 108.3 180)
		(descr "Capacitor SMD 0402")
		(tags "capacitor SMD 0402")
		(property "Reference" "C9"
			(at -2.48 -0.43 0)
			(layer "B.SilkS")
			(effects
				(font
					(size 0.7 0.7)
					(thickness 0.15)
				)
				(justify left bottom mirror)
			)
		)
		(property "Value" "C_100n_0402"
			(at -1.022927 -2.155213 0)
			(layer "B.Fab")
			(effects
				(font
					(size 0.7 0.7)
					(thickness 0.15)
				)
				(justify left bottom mirror)
			)
		)
		(property "Datasheet" "https://www.murata.com/products/productdetail?partno=GRM155R61H104KE14%23"
			(at 0 0 180)
			(layer "F.Fab")
			(hide yes)
			(effects
				(font
					(size 1.27 1.27)
					(thickness 0.15)
				)
			)
		)
		(property "MPN" "GRM155R61H104KE14D"
			(at 0 0 180)
			(unlocked yes)
			(layer "B.Fab")
			(hide yes)
			(effects
				(font
					(size 1 1)
					(thickness 0.15)
				)
				(justify mirror)
			)
		)
		(property "Manufacturer" "Murata"
			(at 0 0 180)
			(unlocked yes)
			(layer "B.Fab")
			(hide yes)
			(effects
				(font
					(size 1 1)
					(thickness 0.15)
				)
				(justify mirror)
			)
		)
		(property "License" "Apache-2.0"
			(at 0 0 180)
			(unlocked yes)
			(layer "B.Fab")
			(hide yes)
			(effects
				(font
					(size 1 1)
					(thickness 0.15)
				)
				(justify mirror)
			)
		)
		(property "Author" "Antmicro"
			(at 0 0 180)
			(unlocked yes)
			(layer "B.Fab")
			(hide yes)
			(effects
				(font
					(size 1 1)
					(thickness 0.15)
				)
				(justify mirror)
			)
		)
		(property "Val" "100n"
			(at 0 0 180)
			(unlocked yes)
			(layer "B.Fab")
			(hide yes)
			(effects
				(font
					(size 1 1)
					(thickness 0.15)
				)
				(justify mirror)
			)
		)
		(property "Voltage" "50V"
			(at 0 0 180)
			(unlocked yes)
			(layer "B.Fab")
			(hide yes)
			(effects
				(font
					(size 1 1)
					(thickness 0.15)
				)
				(justify mirror)
			)
		)
		(property "Dielectric" "X5R"
			(at 0 0 180)
			(unlocked yes)
			(layer "B.Fab")
			(hide yes)
			(effects
				(font
					(size 1 1)
					(thickness 0.15)
				)
				(justify mirror)
			)
		)
		(sheetname "/DDR5 RDIMM/")
		(sheetfile "ddr5-rdimm.kicad_sch")
		(attr smd)
		(fp_rect
			(start -0.925 0.47)
			(end 0.925 -0.47)
			(stroke
				(width 0.05)
				(type default)
			)
			(fill no)
			(layer "B.CrtYd")
		)
		(fp_line
			(start 0.504 0.25)
			(end 0.504 -0.248)
			(stroke
				(width 0.15)
				(type solid)
			)
			(layer "B.Fab")
		)
		(fp_line
			(start 0.504 -0.248)
			(end -0.494 -0.248)
			(stroke
				(width 0.15)
				(type solid)
			)
			(layer "B.Fab")
		)
		(fp_line
			(start -0.494 0.25)
			(end 0.504 0.25)
			(stroke
				(width 0.15)
				(type solid)
			)
			(layer "B.Fab")
		)
		(fp_line
			(start -0.494 -0.248)
			(end -0.494 0.25)
			(stroke
				(width 0.15)
				(type solid)
			)
			(layer "B.Fab")
		)
		(fp_text user "License: Apache-2.0"
			(at -0.939 -5.799 0)
			(layer "B.Fab")
			(effects
				(font
					(size 0.7 0.7)
					(thickness 0.15)
				)
				(justify left bottom mirror)
			)
		)
		(fp_text user "Author: Antmicro"
			(at -0.939 -3.399 0)
			(layer "B.Fab")
			(effects
				(font
					(size 0.7 0.7)
					(thickness 0.15)
				)
				(justify left bottom mirror)
			)
		)
		(fp_text user "${REFERENCE}"
			(at -0.939 -4.599 0)
			(layer "B.Fab")
			(effects
				(font
					(size 0.7 0.7)
					(thickness 0.15)
				)
				(justify left bottom mirror)
			)
		)
		(pad "1" smd roundrect
			(at -0.48 0 180)
			(size 0.59 0.64)
			(layers "B.Cu" "B.Mask" "B.Paste")
			(roundrect_rratio 0.25)
			(net 1 "GND")
			(pintype "passive")
		)
		(pad "2" smd roundrect
			(at 0.48 0 180)
			(size 0.59 0.64)
			(layers "B.Cu" "B.Mask" "B.Paste")
			(roundrect_rratio 0.25)
			(net 687 "VDDQ")
			(pintype "passive")
		)
	)
	(footprint "antmicro-footprints:TP_SMD_1mm"
		(layer "B.Cu")
		(at 227.9 181.8 90)
		(property "Reference" "TP25"
			(at 0.65 0.5 90)
			(layer "B.SilkS")
			(effects
				(font
					(size 0.7 0.7)
					(thickness 0.15)
				)
				(justify right bottom mirror)
			)
		)
		(property "Value" "TP_1mm_SMD"
			(at 0 -1.4 90)
			(layer "B.Fab")
			(effects
				(font
					(size 0.7 0.7)
					(thickness 0.15)
				)
				(justify right bottom mirror)
			)
		)
		(property "MPN" ""
			(at 0 0 90)
			(unlocked yes)
			(layer "B.Fab")
			(hide yes)
			(effects
				(font
					(size 1 1)
					(thickness 0.15)
				)
				(justify mirror)
			)
		)
		(property "Manufacturer" ""
			(at 0 0 90)
			(unlocked yes)
			(layer "B.Fab")
			(hide yes)
			(effects
				(font
					(size 1 1)
					(thickness 0.15)
				)
				(justify mirror)
			)
		)
		(property "Author" "Antmicro"
			(at 0 0 90)
			(unlocked yes)
			(layer "B.Fab")
			(hide yes)
			(effects
				(font
					(size 1 1)
					(thickness 0.15)
				)
				(justify mirror)
			)
		)
		(property "License" "Apache-2.0"
			(at 0 0 90)
			(unlocked yes)
			(layer "B.Fab")
			(hide yes)
			(effects
				(font
					(size 1 1)
					(thickness 0.15)
				)
				(justify mirror)
			)
		)
		(sheetname "/Supply/DC-DC VCCINT/")
		(sheetfile "dc-dc-vccint.kicad_sch")
		(attr exclude_from_pos_files)
		(fp_circle
			(center 0 0)
			(end 0.6 0)
			(stroke
				(width 0.05)
				(type default)
			)
			(fill no)
			(layer "B.CrtYd")
		)
		(fp_text user "License: Apache-2.0"
			(at -0.5 -5.2 270)
			(layer "B.Fab")
			(effects
				(font
					(size 0.7 0.7)
					(thickness 0.15)
				)
				(justify left bottom mirror)
			)
		)
		(fp_text user "Author: Antmicro"
			(at -0.5 -4 270)
			(layer "B.Fab")
			(effects
				(font
					(size 0.7 0.7)
					(thickness 0.15)
				)
				(justify left bottom mirror)
			)
		)
		(fp_text user "${REFERENCE}"
			(at -0.5 -2.8 270)
			(layer "B.Fab")
			(effects
				(font
					(size 0.7 0.7)
					(thickness 0.15)
				)
				(justify left bottom mirror)
			)
		)
		(pad "1" smd circle
			(at 0 0 90)
			(size 1 1)
			(layers "B.Cu" "B.Mask")
			(net 748 "/Supply/DC-DC VCCINT/PWR.~{ALT}2")
			(pinfunction "1")
			(pintype "passive")
		)
	)
	(footprint "antmicro-footprints:C_0603_1608Metric"
		(layer "B.Cu")
		(at 188.5 150.85 -90)
		(descr "Capacitor SMD 0603")
		(tags "capacitor 0603")
		(property "Reference" "C239"
			(at -12.075 30.6 90)
			(layer "B.SilkS")
			(effects
				(font
					(size 0.7 0.7)
					(thickness 0.15)
				)
				(justify left bottom mirror)
			)
		)
		(property "Value" "C_47u_0603"
			(at -1.42757 -1.770288 90)
			(layer "B.Fab")
			(effects
				(font
					(size 0.7 0.7)
					(thickness 0.15)
				)
				(justify left bottom mirror)
			)
		)
		(property "Datasheet" "https://www.murata.com/products/productdetail?partno=GRM188R60J476ME15%23"
			(at 0 0 270)
			(layer "F.Fab")
			(hide yes)
			(effects
				(font
					(size 1.27 1.27)
					(thickness 0.15)
				)
			)
		)
		(property "Manufacturer" "Murata"
			(at 0 0 270)
			(unlocked yes)
			(layer "B.Fab")
			(hide yes)
			(effects
				(font
					(size 1 1)
					(thickness 0.15)
				)
				(justify mirror)
			)
		)
		(property "MPN" "GRM188R60J476ME15D"
			(at 0 0 270)
			(unlocked yes)
			(layer "B.Fab")
			(hide yes)
			(effects
				(font
					(size 1 1)
					(thickness 0.15)
				)
				(justify mirror)
			)
		)
		(property "Val" "47u"
			(at 0 0 270)
			(unlocked yes)
			(layer "B.Fab")
			(hide yes)
			(effects
				(font
					(size 1 1)
					(thickness 0.15)
				)
				(justify mirror)
			)
		)
		(property "License" "Apache-2.0"
			(at 0 0 270)
			(unlocked yes)
			(layer "B.Fab")
			(hide yes)
			(effects
				(font
					(size 1 1)
					(thickness 0.15)
				)
				(justify mirror)
			)
		)
		(property "Author" "Antmicro"
			(at 0 0 270)
			(unlocked yes)
			(layer "B.Fab")
			(hide yes)
			(effects
				(font
					(size 1 1)
					(thickness 0.15)
				)
				(justify mirror)
			)
		)
		(property "Voltage" ""
			(at 0 0 270)
			(unlocked yes)
			(layer "B.Fab")
			(hide yes)
			(effects
				(font
					(size 1 1)
					(thickness 0.15)
				)
				(justify mirror)
			)
		)
		(property "Dielectric" ""
			(at 0 0 270)
			(unlocked yes)
			(layer "B.Fab")
			(hide yes)
			(effects
				(font
					(size 1 1)
					(thickness 0.15)
				)
				(justify mirror)
			)
		)
		(sheetname "/FPGA power/")
		(sheetfile "fpga-power.kicad_sch")
		(attr smd)
		(fp_line
			(start -0.15 0.4)
			(end 0.15 0.4)
			(stroke
				(width 0.15)
				(type solid)
			)
			(layer "B.SilkS")
		)
		(fp_line
			(start -0.15 -0.4)
			(end 0.15 -0.4)
			(stroke
				(width 0.15)
				(type solid)
			)
			(layer "B.SilkS")
		)
		(fp_rect
			(start -1.25 0.65)
			(end 1.25 -0.65)
			(stroke
				(width 0.05)
				(type solid)
			)
			(fill no)
			(layer "B.CrtYd")
		)
		(fp_rect
			(start -0.8 0.4)
			(end 0.8 -0.4)
			(stroke
				(width 0.15)
				(type solid)
			)
			(fill no)
			(layer "B.Fab")
		)
		(fp_text user "License: Apache-2.0"
			(at -1.682 -5.895 90)
			(layer "B.Fab")
			(effects
				(font
					(size 0.7 0.7)
					(thickness 0.15)
				)
				(justify left bottom mirror)
			)
		)
		(fp_text user "Author: Antmicro"
			(at -1.682 -4.894 90)
			(layer "B.Fab")
			(effects
				(font
					(size 0.7 0.7)
					(thickness 0.15)
				)
				(justify left bottom mirror)
			)
		)
		(fp_text user "${REFERENCE}"
			(at -1.682 -3.895 90)
			(layer "B.Fab")
			(effects
				(font
					(size 0.7 0.7)
					(thickness 0.15)
				)
				(justify left bottom mirror)
			)
		)
		(pad "1" smd roundrect
			(at -0.7 0 270)
			(size 0.8 1)
			(layers "B.Cu" "B.Mask" "B.Paste")
			(roundrect_rratio 0.2)
			(net 553 "+0V85")
			(pintype "passive")
		)
		(pad "2" smd roundrect
			(at 0.7 0 270)
			(size 0.8 1)
			(layers "B.Cu" "B.Mask" "B.Paste")
			(roundrect_rratio 0.2)
			(net 1 "GND")
			(pintype "passive")
		)
	)
	(footprint "antmicro-footprints:C_0402_1005Metric"
		(layer "B.Cu")
		(at 143.57 148.17)
		(descr "Capacitor SMD 0402")
		(tags "capacitor SMD 0402")
		(property "Reference" "C160"
			(at 0.9 0.46 0)
			(layer "B.SilkS")
			(effects
				(font
					(size 0.7 0.7)
					(thickness 0.15)
				)
				(justify right bottom mirror)
			)
		)
		(property "Value" "C_100n_0402"
			(at -1.022927 -2.155213 0)
			(layer "B.Fab")
			(effects
				(font
					(size 0.7 0.7)
					(thickness 0.15)
				)
				(justify right bottom mirror)
			)
		)
		(property "Datasheet" "https://www.murata.com/products/productdetail?partno=GRM155R61H104KE14%23"
			(at 0 0 0)
			(layer "F.Fab")
			(hide yes)
			(effects
				(font
					(size 1.27 1.27)
					(thickness 0.15)
				)
			)
		)
		(property "MPN" "GRM155R61H104KE14D"
			(at 0 0 0)
			(unlocked yes)
			(layer "B.Fab")
			(hide yes)
			(effects
				(font
					(size 1 1)
					(thickness 0.15)
				)
				(justify mirror)
			)
		)
		(property "Manufacturer" "Murata"
			(at 0 0 0)
			(unlocked yes)
			(layer "B.Fab")
			(hide yes)
			(effects
				(font
					(size 1 1)
					(thickness 0.15)
				)
				(justify mirror)
			)
		)
		(property "License" "Apache-2.0"
			(at 0 0 0)
			(unlocked yes)
			(layer "B.Fab")
			(hide yes)
			(effects
				(font
					(size 1 1)
					(thickness 0.15)
				)
				(justify mirror)
			)
		)
		(property "Author" "Antmicro"
			(at 0 0 0)
			(unlocked yes)
			(layer "B.Fab")
			(hide yes)
			(effects
				(font
					(size 1 1)
					(thickness 0.15)
				)
				(justify mirror)
			)
		)
		(property "Val" "100n"
			(at 0 0 0)
			(unlocked yes)
			(layer "B.Fab")
			(hide yes)
			(effects
				(font
					(size 1 1)
					(thickness 0.15)
				)
				(justify mirror)
			)
		)
		(property "Voltage" "50V"
			(at 0 0 0)
			(unlocked yes)
			(layer "B.Fab")
			(hide yes)
			(effects
				(font
					(size 1 1)
					(thickness 0.15)
				)
				(justify mirror)
			)
		)
		(property "Dielectric" "X5R"
			(at 0 0 0)
			(unlocked yes)
			(layer "B.Fab")
			(hide yes)
			(effects
				(font
					(size 1 1)
					(thickness 0.15)
				)
				(justify mirror)
			)
		)
		(sheetname "/Ethernet/")
		(sheetfile "ethernet.kicad_sch")
		(attr smd)
		(fp_rect
			(start -0.925 0.47)
			(end 0.925 -0.47)
			(stroke
				(width 0.05)
				(type default)
			)
			(fill no)
			(layer "B.CrtYd")
		)
		(fp_line
			(start -0.494 -0.248)
			(end -0.494 0.25)
			(stroke
				(width 0.15)
				(type solid)
			)
			(layer "B.Fab")
		)
		(fp_line
			(start -0.494 0.25)
			(end 0.504 0.25)
			(stroke
				(width 0.15)
				(type solid)
			)
			(layer "B.Fab")
		)
		(fp_line
			(start 0.504 -0.248)
			(end -0.494 -0.248)
			(stroke
				(width 0.15)
				(type solid)
			)
			(layer "B.Fab")
		)
		(fp_line
			(start 0.504 0.25)
			(end 0.504 -0.248)
			(stroke
				(width 0.15)
				(type solid)
			)
			(layer "B.Fab")
		)
		(fp_text user "Author: Antmicro"
			(at -0.939 -3.399 180)
			(layer "B.Fab")
			(effects
				(font
					(size 0.7 0.7)
					(thickness 0.15)
				)
				(justify left bottom mirror)
			)
		)
		(fp_text user "${REFERENCE}"
			(at -0.939 -4.599 180)
			(layer "B.Fab")
			(effects
				(font
					(size 0.7 0.7)
					(thickness 0.15)
				)
				(justify left bottom mirror)
			)
		)
		(fp_text user "License: Apache-2.0"
			(at -0.939 -5.799 180)
			(layer "B.Fab")
			(effects
				(font
					(size 0.7 0.7)
					(thickness 0.15)
				)
				(justify left bottom mirror)
			)
		)
		(pad "1" smd roundrect
			(at -0.48 0)
			(size 0.59 0.64)
			(layers "B.Cu" "B.Mask" "B.Paste")
			(roundrect_rratio 0.25)
			(net 1 "GND")
			(pintype "passive")
		)
		(pad "2" smd roundrect
			(at 0.48 0)
			(size 0.59 0.64)
			(layers "B.Cu" "B.Mask" "B.Paste")
			(roundrect_rratio 0.25)
			(net 797 "+1V8")
			(pintype "passive")
		)
	)
	(footprint "antmicro-footprints:R_0402_1005Metric_EIA"
		(layer "B.Cu")
		(at 197 156.5 -90)
		(descr "Resistor SMD 0402 (1005 Metric), square (rectangular) end terminal, IPC_7351 nominal, (Body size source: IPC-SM-782 page 76, https://www.pcb-3d.com/wordpress/wp-content/uploads/ipc-sm-782a_amendment_1_and_2.pdf)")
		(tags "resistor 0402")
		(property "Reference" "R17"
			(at -11.9 30.575 90)
			(layer "B.SilkS")
			(effects
				(font
					(size 0.7 0.7)
					(thickness 0.15)
				)
				(justify left bottom mirror)
			)
		)
		(property "Value" "R_10k_0402"
			(at 0 -1.169 90)
			(layer "B.Fab")
			(effects
				(font
					(size 0.7 0.7)
					(thickness 0.15)
				)
				(justify left bottom mirror)
			)
		)
		(property "Datasheet" "https://www.bourns.com/docs/product-datasheets/cr.pdf"
			(at 0 0 270)
			(layer "F.Fab")
			(hide yes)
			(effects
				(font
					(size 1.27 1.27)
					(thickness 0.15)
				)
			)
		)
		(property "MPN" "CR0402-FX-1002GLF"
			(at 0 0 270)
			(unlocked yes)
			(layer "B.Fab")
			(hide yes)
			(effects
				(font
					(size 1 1)
					(thickness 0.15)
				)
				(justify mirror)
			)
		)
		(property "Manufacturer" "Bourns"
			(at 0 0 270)
			(unlocked yes)
			(layer "B.Fab")
			(hide yes)
			(effects
				(font
					(size 1 1)
					(thickness 0.15)
				)
				(justify mirror)
			)
		)
		(property "License" "Apache-2.0"
			(at 0 0 270)
			(unlocked yes)
			(layer "B.Fab")
			(hide yes)
			(effects
				(font
					(size 1 1)
					(thickness 0.15)
				)
				(justify mirror)
			)
		)
		(property "Author" "Antmicro"
			(at 0 0 270)
			(unlocked yes)
			(layer "B.Fab")
			(hide yes)
			(effects
				(font
					(size 1 1)
					(thickness 0.15)
				)
				(justify mirror)
			)
		)
		(property "Val" "10k"
			(at 0 0 270)
			(unlocked yes)
			(layer "B.Fab")
			(hide yes)
			(effects
				(font
					(size 1 1)
					(thickness 0.15)
				)
				(justify mirror)
			)
		)
		(property "Tolerance" "1%"
			(at 0 0 270)
			(unlocked yes)
			(layer "B.Fab")
			(hide yes)
			(effects
				(font
					(size 1 1)
					(thickness 0.15)
				)
				(justify mirror)
			)
		)
		(sheetname "/FPGA Config/")
		(sheetfile "fpga-config.kicad_sch")
		(attr smd)
		(fp_rect
			(start -0.95 0.45)
			(end 0.95 -0.45)
			(stroke
				(width 0.05)
				(type default)
			)
			(fill no)
			(layer "B.CrtYd")
		)
		(fp_line
			(start -0.5 0.25)
			(end 0.499 0.25)
			(stroke
				(width 0.15)
				(type solid)
			)
			(layer "B.Fab")
		)
		(fp_line
			(start 0.499 0.25)
			(end 0.499 -0.249)
			(stroke
				(width 0.15)
				(type solid)
			)
			(layer "B.Fab")
		)
		(fp_line
			(start -0.5 -0.249)
			(end -0.5 0.25)
			(stroke
				(width 0.15)
				(type solid)
			)
			(layer "B.Fab")
		)
		(fp_line
			(start 0.499 -0.249)
			(end -0.5 -0.249)
			(stroke
				(width 0.15)
				(type solid)
			)
			(layer "B.Fab")
		)
		(fp_text user "Author: Antmicro"
			(at -0.95 -5.569 90)
			(layer "B.Fab")
			(effects
				(font
					(size 0.7 0.7)
					(thickness 0.15)
				)
				(justify left bottom mirror)
			)
		)
		(fp_text user "${REFERENCE}"
			(at -0.95 -3.169 90)
			(layer "B.Fab")
			(effects
				(font
					(size 0.7 0.7)
					(thickness 0.15)
				)
				(justify left bottom mirror)
			)
		)
		(fp_text user "License: Apache-2.0"
			(at -0.95 -4.369 90)
			(layer "B.Fab")
			(effects
				(font
					(size 0.7 0.7)
					(thickness 0.15)
				)
				(justify left bottom mirror)
			)
		)
		(pad "1" smd roundrect
			(at -0.5 0 180)
			(size 0.6 0.6)
			(layers "B.Cu" "B.Mask" "B.Paste")
			(roundrect_rratio 0.25)
			(net 356 "/FPGA Config/MODE0")
			(pintype "passive")
		)
		(pad "2" smd roundrect
			(at 0.499 0 270)
			(size 0.6 0.6)
			(layers "B.Cu" "B.Mask" "B.Paste")
			(roundrect_rratio 0.25)
			(net 797 "+1V8")
			(pintype "passive")
		)
	)
)
